(kicad_pcb
	(version 20260206)
	(generator "pcbnew")
	(generator_version "10.0")
	(general
		(thickness 1.6)
		(legacy_teardrops no)
	)
	(paper "A4")
	(title_block
		(title "01162023_DA0F0TEBIF0_F0T_Expander_BD_F_brd_V02_OCP.brd")
		(comment 1 "Grand Teton / footprints 2514-2521 of 9728")
	)
	(layers
		(0 "F.Cu" signal "TOP")
		(4 "In1.Cu" signal "GND")
		(6 "In2.Cu" signal "VCC")
		(8 "In3.Cu" signal "VCC1")
		(10 "In4.Cu" signal "GND1")
		(12 "In5.Cu" signal "IN1")
		(14 "In6.Cu" signal "GND2")
		(16 "In7.Cu" signal "IN2")
		(18 "In8.Cu" signal "GND3")
		(20 "In9.Cu" signal "IN3")
		(22 "In10.Cu" signal "GND4")
		(24 "In11.Cu" signal "IN4")
		(26 "In12.Cu" signal "GND5")
		(28 "In13.Cu" signal "IN5")
		(30 "In14.Cu" signal "GND6")
		(32 "In15.Cu" signal "IN6")
		(34 "In16.Cu" signal "GND7")
		(2 "B.Cu" signal "BOTTOM")
		(9 "F.Adhes" user "F.Adhesive")
		(11 "B.Adhes" user "B.Adhesive")
		(13 "F.Paste" user "Package Geometry/Pastemask Top")
		(15 "B.Paste" user "Package Geometry/Pastemask Bottom")
		(5 "F.SilkS" user "Ref Des/Silkscreen Top")
		(7 "B.SilkS" user "Ref Des/Silkscreen Bottom")
		(1 "F.Mask" user "Board Geometry/Soldermask Top")
		(3 "B.Mask" user "Board Geometry/Soldermask Bottom")
		(17 "Dwgs.User" user "User.Drawings")
		(19 "Cmts.User" user "User.Comments")
		(21 "Eco1.User" user "User.Eco1")
		(23 "Eco2.User" user "User.Eco2")
		(25 "Edge.Cuts" user "Board Geometry/Outline")
		(27 "Margin" user)
		(31 "F.CrtYd" user "Package Geometry/Place Bound Top")
		(29 "B.CrtYd" user "Package Geometry/Place Bound Bottom")
		(35 "F.Fab" user "Ref Des/Assembly Top")
		(33 "B.Fab" user "Ref Des/Assembly Bottom")
	)
	(footprint ""
		(layer "F.Cu")
		(at 138.061192 -37.951156)
		(property "Reference" "Q221"
			(at -0.063246 -1.936242 0)
			(unlocked yes)
			(layer "F.SilkS")
			(effects
				(font
					(size 0.7874 0.5842)
					(thickness 0.1524)
				)
			)
		)
		(property "Value" ""
			(at 0 0 0)
			(layer "F.Fab")
			(effects
				(font
					(size 1.27 1.27)
				)
			)
		)
		(duplicate_pad_numbers_are_jumpers no)
		(fp_line
			(start -1.376172 -1.199896)
			(end -0.508 -1.199896)
			(stroke
				(width 0.1524)
				(type default)
			)
			(layer "F.SilkS")
		)
		(fp_line
			(start -1.376172 1.199896)
			(end -1.376172 -1.199896)
			(stroke
				(width 0.1524)
				(type default)
			)
			(layer "F.SilkS")
		)
		(fp_line
			(start -0.508 -1.199896)
			(end 0 -0.762)
			(stroke
				(width 0.1524)
				(type default)
			)
			(layer "F.SilkS")
		)
		(fp_line
			(start 0 -0.762)
			(end 0.508 -1.199896)
			(stroke
				(width 0.1524)
				(type default)
			)
			(layer "F.SilkS")
		)
		(fp_line
			(start 0.508 -1.199896)
			(end 1.376172 -1.199896)
			(stroke
				(width 0.1524)
				(type default)
			)
			(layer "F.SilkS")
		)
		(fp_line
			(start 1.376172 -1.199896)
			(end 1.376172 1.199896)
			(stroke
				(width 0.1524)
				(type default)
			)
			(layer "F.SilkS")
		)
		(fp_line
			(start 1.376172 1.199896)
			(end -1.376172 1.199896)
			(stroke
				(width 0.1524)
				(type default)
			)
			(layer "F.SilkS")
		)
		(fp_poly
			(pts
				(xy -1.474216 -0.832612) (xy -1.74371 -1.64084) (xy -2.282444 -1.101852)
			)
			(stroke
				(width 0)
				(type default)
			)
			(fill yes)
			(layer "F.SilkS")
		)
		(fp_line
			(start -0.674878 -1.100074)
			(end 0.674878 -1.100074)
			(stroke
				(width 0.1)
				(type default)
			)
			(layer "F.Fab")
		)
		(fp_line
			(start -0.674878 1.100074)
			(end -0.674878 -1.100074)
			(stroke
				(width 0.1)
				(type default)
			)
			(layer "F.Fab")
		)
		(fp_line
			(start 0.674878 -1.100074)
			(end 0.674878 1.100074)
			(stroke
				(width 0.1)
				(type default)
			)
			(layer "F.Fab")
		)
		(fp_line
			(start 0.674878 1.100074)
			(end -0.674878 1.100074)
			(stroke
				(width 0.1)
				(type default)
			)
			(layer "F.Fab")
		)
		(fp_poly
			(pts
				(xy -1.4605 -0.7493) (xy -2.2225 -1.1303) (xy -2.2225 -0.3683)
			)
			(stroke
				(width 0)
				(type default)
			)
			(fill yes)
			(layer "F.Fab")
		)
		(pad "1" smd rect
			(at -0.899922 -0.750062 270)
			(size 0.6096 0.6096)
			(layers "F.Cu" "F.Mask" "F.Paste")
			(net "GND")
		)
		(pad "2" smd rect
			(at -0.899922 0 270)
			(size 0.4064 0.6096)
			(layers "F.Cu" "F.Mask" "F.Paste")
			(net "P3V3_SSD5_PG_G1")
		)
		(pad "3" smd rect
			(at -0.899922 0.750062 270)
			(size 0.6096 0.6096)
			(layers "F.Cu" "F.Mask" "F.Paste")
			(net "PWRGD_P3V3_SSD5_D")
		)
		(pad "4" smd rect
			(at 0.899922 0.750062 270)
			(size 0.6096 0.6096)
			(layers "F.Cu" "F.Mask" "F.Paste")
			(net "GND")
		)
		(pad "5" smd rect
			(at 0.899922 0 270)
			(size 0.4064 0.6096)
			(layers "F.Cu" "F.Mask" "F.Paste")
			(net "P3V3_SSD5_PG_G2")
		)
		(pad "6" smd rect
			(at 0.899922 -0.750062 270)
			(size 0.6096 0.6096)
			(layers "F.Cu" "F.Mask" "F.Paste")
			(net "P3V3_SSD5_PG_G2")
		)
	)
	(footprint ""
		(layer "F.Cu")
		(at 461.734408 -265.876024)
		(property "Reference" "C4406"
			(at 0 0 0)
			(layer "F.SilkS")
			(hide yes)
			(effects
				(font
					(size 1.27 1.27)
				)
			)
		)
		(property "Value" ""
			(at 0 0 0)
			(layer "F.Fab")
			(effects
				(font
					(size 1.27 1.27)
				)
			)
		)
		(duplicate_pad_numbers_are_jumpers no)
		(fp_line
			(start -0.299974 -0.150114)
			(end 0.299974 -0.150114)
			(stroke
				(width 0.1)
				(type default)
			)
			(layer "F.Fab")
		)
		(fp_line
			(start -0.299974 0.150114)
			(end -0.299974 -0.150114)
			(stroke
				(width 0.1)
				(type default)
			)
			(layer "F.Fab")
		)
		(fp_line
			(start 0.299974 -0.150114)
			(end 0.299974 0.150114)
			(stroke
				(width 0.1)
				(type default)
			)
			(layer "F.Fab")
		)
		(fp_line
			(start 0.299974 0.150114)
			(end -0.299974 0.150114)
			(stroke
				(width 0.1)
				(type default)
			)
			(layer "F.Fab")
		)
		(pad "1" smd rect
			(at -0.2667 0)
			(size 0.3048 0.381)
			(layers "F.Cu" "F.Mask" "F.Paste")
			(net "P1V25_SERDES_VDDPLL_PEX3")
		)
		(pad "2" smd rect
			(at 0.2667 0)
			(size 0.3048 0.381)
			(layers "F.Cu" "F.Mask" "F.Paste")
			(net "GND")
		)
	)
	(footprint ""
		(layer "F.Cu")
		(at 148.417534 -113.558574 -90)
		(property "Reference" "C4000"
			(at 0 0 270)
			(layer "F.SilkS")
			(hide yes)
			(effects
				(font
					(size 1.27 1.27)
				)
			)
		)
		(property "Value" ""
			(at 0 0 270)
			(layer "F.Fab")
			(effects
				(font
					(size 1.27 1.27)
				)
			)
		)
		(duplicate_pad_numbers_are_jumpers no)
		(fp_line
			(start -0.7874 0.4064)
			(end -0.7874 -0.4064)
			(stroke
				(width 0.1524)
				(type default)
			)
			(layer "F.SilkS")
		)
		(fp_line
			(start 0.7874 0.4064)
			(end -0.7874 0.4064)
			(stroke
				(width 0.1524)
				(type default)
			)
			(layer "F.SilkS")
		)
		(fp_line
			(start -0.7874 -0.4064)
			(end 0.7874 -0.4064)
			(stroke
				(width 0.1524)
				(type default)
			)
			(layer "F.SilkS")
		)
		(fp_line
			(start 0.7874 -0.4064)
			(end 0.7874 0.4064)
			(stroke
				(width 0.1524)
				(type default)
			)
			(layer "F.SilkS")
		)
		(fp_line
			(start -0.67945 0.3048)
			(end -0.67945 -0.305054)
			(stroke
				(width 0.1)
				(type default)
			)
			(layer "F.Fab")
		)
		(fp_line
			(start -0.12065 0.3048)
			(end -0.67945 0.3048)
			(stroke
				(width 0.1)
				(type default)
			)
			(layer "F.Fab")
		)
		(fp_line
			(start 0.120396 0.3048)
			(end 0.120396 0.2794)
			(stroke
				(width 0.1)
				(type default)
			)
			(layer "F.Fab")
		)
		(fp_line
			(start 0.67945 0.3048)
			(end 0.120396 0.3048)
			(stroke
				(width 0.1)
				(type default)
			)
			(layer "F.Fab")
		)
		(fp_line
			(start -0.12065 0.2794)
			(end -0.12065 0.3048)
			(stroke
				(width 0.1)
				(type default)
			)
			(layer "F.Fab")
		)
		(fp_line
			(start 0.120396 0.2794)
			(end -0.12065 0.2794)
			(stroke
				(width 0.1)
				(type default)
			)
			(layer "F.Fab")
		)
		(fp_line
			(start -0.12065 -0.2794)
			(end 0.12065 -0.2794)
			(stroke
				(width 0.1)
				(type default)
			)
			(layer "F.Fab")
		)
		(fp_line
			(start 0.12065 -0.2794)
			(end 0.12065 -0.3048)
			(stroke
				(width 0.1)
				(type default)
			)
			(layer "F.Fab")
		)
		(fp_line
			(start 0.12065 -0.3048)
			(end 0.67945 -0.3048)
			(stroke
				(width 0.1)
				(type default)
			)
			(layer "F.Fab")
		)
		(fp_line
			(start 0.67945 -0.3048)
			(end 0.67945 0.3048)
			(stroke
				(width 0.1)
				(type default)
			)
			(layer "F.Fab")
		)
		(fp_line
			(start -0.67945 -0.305054)
			(end -0.12065 -0.305054)
			(stroke
				(width 0.1)
				(type default)
			)
			(layer "F.Fab")
		)
		(fp_line
			(start -0.12065 -0.305054)
			(end -0.12065 -0.2794)
			(stroke
				(width 0.1)
				(type default)
			)
			(layer "F.Fab")
		)
		(pad "1" smd circle
			(at -0.40005 0 270)
			(size 0 0)
			(layers "F.Cu" "F.Mask" "F.Paste")
			(net "PRSNT_NIC2_R_N")
		)
		(pad "2" smd circle
			(at 0.40005 0 270)
			(size 0 0)
			(layers "F.Cu" "F.Mask" "F.Paste")
			(net "GND")
		)
	)
	(footprint ""
		(layer "F.Cu")
		(at 188.534548 -30.94609 180)
		(property "Reference" "C296"
			(at 0 0 180)
			(layer "F.SilkS")
			(hide yes)
			(effects
				(font
					(size 1.27 1.27)
				)
			)
		)
		(property "Value" ""
			(at 0 0 180)
			(layer "F.Fab")
			(effects
				(font
					(size 1.27 1.27)
				)
			)
		)
		(duplicate_pad_numbers_are_jumpers no)
		(fp_line
			(start 0.299974 0.150114)
			(end -0.299974 0.150114)
			(stroke
				(width 0.1)
				(type default)
			)
			(layer "F.Fab")
		)
		(fp_line
			(start 0.299974 -0.150114)
			(end 0.299974 0.150114)
			(stroke
				(width 0.1)
				(type default)
			)
			(layer "F.Fab")
		)
		(fp_line
			(start -0.299974 0.150114)
			(end -0.299974 -0.150114)
			(stroke
				(width 0.1)
				(type default)
			)
			(layer "F.Fab")
		)
		(fp_line
			(start -0.299974 -0.150114)
			(end 0.299974 -0.150114)
			(stroke
				(width 0.1)
				(type default)
			)
			(layer "F.Fab")
		)
		(pad "1" smd rect
			(at -0.2667 0 180)
			(size 0.3048 0.381)
			(layers "F.Cu" "F.Mask" "F.Paste")
			(net "P5E_PEX1_STN2_TX_DP<37>")
		)
		(pad "2" smd rect
			(at 0.2667 0 180)
			(size 0.3048 0.381)
			(layers "F.Cu" "F.Mask" "F.Paste")
			(net "P5E_PEX1_STN2_TX_C_DP<37>")
		)
	)
	(footprint ""
		(layer "F.Cu")
		(at 400.543776 -44.87291)
		(property "Reference" "R650"
			(at 0 0 0)
			(layer "F.SilkS")
			(hide yes)
			(effects
				(font
					(size 1.27 1.27)
				)
			)
		)
		(property "Value" ""
			(at 0 0 0)
			(layer "F.Fab")
			(effects
				(font
					(size 1.27 1.27)
				)
			)
		)
		(duplicate_pad_numbers_are_jumpers no)
		(fp_line
			(start -0.7874 -0.4064)
			(end 0.7874 -0.4064)
			(stroke
				(width 0.1524)
				(type default)
			)
			(layer "F.SilkS")
		)
		(fp_line
			(start -0.7874 0.4064)
			(end -0.7874 -0.4064)
			(stroke
				(width 0.1524)
				(type default)
			)
			(layer "F.SilkS")
		)
		(fp_line
			(start 0.7874 -0.4064)
			(end 0.7874 0.4064)
			(stroke
				(width 0.1524)
				(type default)
			)
			(layer "F.SilkS")
		)
		(fp_line
			(start 0.7874 0.4064)
			(end -0.7874 0.4064)
			(stroke
				(width 0.1524)
				(type default)
			)
			(layer "F.SilkS")
		)
		(fp_line
			(start -0.67945 -0.305054)
			(end -0.12065 -0.305054)
			(stroke
				(width 0.1)
				(type default)
			)
			(layer "F.Fab")
		)
		(fp_line
			(start -0.67945 0.3048)
			(end -0.67945 -0.305054)
			(stroke
				(width 0.1)
				(type default)
			)
			(layer "F.Fab")
		)
		(fp_line
			(start -0.12065 -0.305054)
			(end -0.12065 -0.2794)
			(stroke
				(width 0.1)
				(type default)
			)
			(layer "F.Fab")
		)
		(fp_line
			(start -0.12065 -0.2794)
			(end 0.12065 -0.2794)
			(stroke
				(width 0.1)
				(type default)
			)
			(layer "F.Fab")
		)
		(fp_line
			(start -0.12065 0.2794)
			(end -0.12065 0.3048)
			(stroke
				(width 0.1)
				(type default)
			)
			(layer "F.Fab")
		)
		(fp_line
			(start -0.12065 0.3048)
			(end -0.67945 0.3048)
			(stroke
				(width 0.1)
				(type default)
			)
			(layer "F.Fab")
		)
		(fp_line
			(start 0.120396 0.2794)
			(end -0.12065 0.2794)
			(stroke
				(width 0.1)
				(type default)
			)
			(layer "F.Fab")
		)
		(fp_line
			(start 0.120396 0.3048)
			(end 0.120396 0.2794)
			(stroke
				(width 0.1)
				(type default)
			)
			(layer "F.Fab")
		)
		(fp_line
			(start 0.12065 -0.3048)
			(end 0.67945 -0.3048)
			(stroke
				(width 0.1)
				(type default)
			)
			(layer "F.Fab")
		)
		(fp_line
			(start 0.12065 -0.2794)
			(end 0.12065 -0.3048)
			(stroke
				(width 0.1)
				(type default)
			)
			(layer "F.Fab")
		)
		(fp_line
			(start 0.67945 -0.3048)
			(end 0.67945 0.3048)
			(stroke
				(width 0.1)
				(type default)
			)
			(layer "F.Fab")
		)
		(fp_line
			(start 0.67945 0.3048)
			(end 0.120396 0.3048)
			(stroke
				(width 0.1)
				(type default)
			)
			(layer "F.Fab")
		)
		(pad "1" smd circle
			(at -0.40005 0)
			(size 0 0)
			(layers "F.Cu" "F.Mask" "F.Paste")
			(net "SSD13_ADC_A0")
		)
		(pad "2" smd circle
			(at 0.40005 0)
			(size 0 0)
			(layers "F.Cu" "F.Mask" "F.Paste")
			(net "P3V3_AUX")
		)
	)
	(footprint ""
		(layer "F.Cu")
		(at 458.903324 -553.91304 180)
		(property "Reference" "SCREW_SSD14_2"
			(at -5.6007 -1.402334 0)
			(unlocked yes)
			(layer "B.SilkS")
			(effects
				(font
					(size 0.7874 0.5842)
					(thickness 0.1524)
				)
				(justify mirror)
			)
		)
		(property "Value" ""
			(at 0 0 180)
			(layer "F.Fab")
			(effects
				(font
					(size 1.27 1.27)
				)
			)
		)
		(duplicate_pad_numbers_are_jumpers no)
		(pad "1" thru_hole circle
			(at 0 0 180)
			(size 0.4572 0.4572)
			(drill 0.2032)
			(layers "*.Cu" "*.Mask")
			(remove_unused_layers no)
			(net "Net_9145")
			(clearance 0.127)
			(thermal_gap 0.127)
			(padstack
				(mode front_inner_back)
				(layer "Inner"
					(shape circle)
					(size 0.4572 0.4572)
					(clearance 0.127)
				)
				(layer "B.Cu"
					(shape circle)
					(size 0.508 0.508)
					(clearance 0.1016)
				)
			)
		)
	)
	(footprint ""
		(layer "F.Cu")
		(at 431.946812 -350.098614 90)
		(property "Reference" "C804"
			(at 0 0 90)
			(layer "F.SilkS")
			(hide yes)
			(effects
				(font
					(size 1.27 1.27)
				)
			)
		)
		(property "Value" ""
			(at 0 0 90)
			(layer "F.Fab")
			(effects
				(font
					(size 1.27 1.27)
				)
			)
		)
		(duplicate_pad_numbers_are_jumpers no)
		(fp_line
			(start 0.299974 -0.150114)
			(end 0.299974 0.150114)
			(stroke
				(width 0.1)
				(type default)
			)
			(layer "F.Fab")
		)
		(fp_line
			(start -0.299974 -0.150114)
			(end 0.299974 -0.150114)
			(stroke
				(width 0.1)
				(type default)
			)
			(layer "F.Fab")
		)
		(fp_line
			(start 0.299974 0.150114)
			(end -0.299974 0.150114)
			(stroke
				(width 0.1)
				(type default)
			)
			(layer "F.Fab")
		)
		(fp_line
			(start -0.299974 0.150114)
			(end -0.299974 -0.150114)
			(stroke
				(width 0.1)
				(type default)
			)
			(layer "F.Fab")
		)
		(pad "1" smd rect
			(at -0.2667 0 90)
			(size 0.3048 0.381)
			(layers "F.Cu" "F.Mask" "F.Paste")
			(net "P5E_PEX3_STN7_TX_DP<122>")
		)
		(pad "2" smd rect
			(at 0.2667 0 90)
			(size 0.3048 0.381)
			(layers "F.Cu" "F.Mask" "F.Paste")
			(net "P5E_PEX3_STN7_TX_C_DP<122>")
		)
	)
	(footprint ""
		(layer "F.Cu")
		(at 241.600736 -201.29627 180)
		(property "Reference" "R4859"
			(at 0 0 180)
			(layer "F.SilkS")
			(hide yes)
			(effects
				(font
					(size 1.27 1.27)
				)
			)
		)
		(property "Value" ""
			(at 0 0 180)
			(layer "F.Fab")
			(effects
				(font
					(size 1.27 1.27)
				)
			)
		)
		(duplicate_pad_numbers_are_jumpers no)
		(fp_line
			(start 0.7874 0.4064)
			(end -0.7874 0.4064)
			(stroke
				(width 0.1524)
				(type default)
			)
			(layer "F.SilkS")
		)
		(fp_line
			(start 0.7874 -0.4064)
			(end 0.7874 0.4064)
			(stroke
				(width 0.1524)
				(type default)
			)
			(layer "F.SilkS")
		)
		(fp_line
			(start -0.7874 0.4064)
			(end -0.7874 -0.4064)
			(stroke
				(width 0.1524)
				(type default)
			)
			(layer "F.SilkS")
		)
		(fp_line
			(start -0.7874 -0.4064)
			(end 0.7874 -0.4064)
			(stroke
				(width 0.1524)
				(type default)
			)
			(layer "F.SilkS")
		)
		(fp_line
			(start 0.67945 0.3048)
			(end 0.120396 0.3048)
			(stroke
				(width 0.1)
				(type default)
			)
			(layer "F.Fab")
		)
		(fp_line
			(start 0.67945 -0.3048)
			(end 0.67945 0.3048)
			(stroke
				(width 0.1)
				(type default)
			)
			(layer "F.Fab")
		)
		(fp_line
			(start 0.12065 -0.2794)
			(end 0.12065 -0.3048)
			(stroke
				(width 0.1)
				(type default)
			)
			(layer "F.Fab")
		)
		(fp_line
			(start 0.12065 -0.3048)
			(end 0.67945 -0.3048)
			(stroke
				(width 0.1)
				(type default)
			)
			(layer "F.Fab")
		)
		(fp_line
			(start 0.120396 0.3048)
			(end 0.120396 0.2794)
			(stroke
				(width 0.1)
				(type default)
			)
			(layer "F.Fab")
		)
		(fp_line
			(start 0.120396 0.2794)
			(end -0.12065 0.2794)
			(stroke
				(width 0.1)
				(type default)
			)
			(layer "F.Fab")
		)
		(fp_line
			(start -0.12065 0.3048)
			(end -0.67945 0.3048)
			(stroke
				(width 0.1)
				(type default)
			)
			(layer "F.Fab")
		)
		(fp_line
			(start -0.12065 0.2794)
			(end -0.12065 0.3048)
			(stroke
				(width 0.1)
				(type default)
			)
			(layer "F.Fab")
		)
		(fp_line
			(start -0.12065 -0.2794)
			(end 0.12065 -0.2794)
			(stroke
				(width 0.1)
				(type default)
			)
			(layer "F.Fab")
		)
		(fp_line
			(start -0.12065 -0.305054)
			(end -0.12065 -0.2794)
			(stroke
				(width 0.1)
				(type default)
			)
			(layer "F.Fab")
		)
		(fp_line
			(start -0.67945 0.3048)
			(end -0.67945 -0.305054)
			(stroke
				(width 0.1)
				(type default)
			)
			(layer "F.Fab")
		)
		(fp_line
			(start -0.67945 -0.305054)
			(end -0.12065 -0.305054)
			(stroke
				(width 0.1)
				(type default)
			)
			(layer "F.Fab")
		)
		(pad "1" smd circle
			(at -0.40005 0 180)
			(size 0 0)
			(layers "F.Cu" "F.Mask" "F.Paste")
			(net "P3V3_AUX")
		)
		(pad "2" smd circle
			(at 0.40005 0 180)
			(size 0 0)
			(layers "F.Cu" "F.Mask" "F.Paste")
			(net "PU_CLK_25M_BIC_EN")
		)
	)
)
